# BASEBOARD_FAB2 (Tioga Pass) — schematic netlist excerpt (pin names and nets, part order shuffled) for the footprints in the layout excerpt that follows; sources: Cadence DE-HDL packaged netlist, KiCad conversion of Wiwynn_Tioga_Pass_MB.brd

R8E39  RES  24.9K 1% CHIP  pkg 0402  page 241 : A = VR_P5V_STBY_COMP ; B = VR_P5V_STBY_RC_COMP
C4D12  CAP_A  22.0UF 4V 20% X6S  pkg 0603V  page 204 : A = PVCCIN_CPU0 ; B = GND
C7B18  CAP_A  22.0UF 4V 20% X6S  pkg 0603V  page 131 : A = P1V05_PCH_STBY ; B = GND

(kicad_pcb
	(version 20260206)
	(generator "pcbnew")
	(generator_version "10.0")
	(general
		(thickness 1.6)
		(legacy_teardrops no)
	)
	(paper "A4")
	(title_block
		(title "Wiwynn_Tioga_Pass_MB.brd")
		(comment 1 "Tioga Pass / footprints 1665-1667 of 4770")
	)
	(layers
		(0 "F.Cu" signal "TOP")
		(4 "In1.Cu" signal "L2GND")
		(6 "In2.Cu" signal "L3")
		(8 "In3.Cu" signal "L4GND")
		(10 "In4.Cu" signal "L5")
		(12 "In5.Cu" signal "L6GND")
		(14 "In6.Cu" signal "L7VCC")
		(16 "In7.Cu" signal "L8VCC")
		(18 "In8.Cu" signal "L9GND")
		(20 "In9.Cu" signal "L10")
		(22 "In10.Cu" signal "L11GND")
		(24 "In11.Cu" signal "L12")
		(26 "In12.Cu" signal "L13GND")
		(2 "B.Cu" signal "BOTTOM")
		(9 "F.Adhes" user "F.Adhesive")
		(11 "B.Adhes" user "B.Adhesive")
		(13 "F.Paste" user "Package Geometry/Pastemask Top")
		(15 "B.Paste" user "Package Geometry/Pastemask Bottom")
		(5 "F.SilkS" user "Ref Des/Silkscreen Top")
		(7 "B.SilkS" user "Ref Des/Silkscreen Bottom")
		(1 "F.Mask" user "Board Geometry/Soldermask Top")
		(3 "B.Mask" user "Board Geometry/Soldermask Bottom")
		(17 "Dwgs.User" user "User.Drawings")
		(19 "Cmts.User" user "User.Comments")
		(21 "Eco1.User" user "User.Eco1")
		(23 "Eco2.User" user "User.Eco2")
		(25 "Edge.Cuts" user "Board Geometry/Outline")
		(27 "Margin" user)
		(31 "F.CrtYd" user "Package Geometry/Place Bound Top")
		(29 "B.CrtYd" user "Package Geometry/Place Bound Bottom")
		(35 "F.Fab" user "Ref Des/Assembly Top")
		(33 "B.Fab" user "Ref Des/Assembly Bottom")
	)
	(footprint ""
		(layer "F.Cu")
		(at 392.785346 -64.959738 90)
		(property "Reference" "R8E39"
			(at 0 0 90)
			(layer "F.SilkS")
			(hide yes)
			(effects
				(font
					(size 1.27 1.27)
				)
			)
		)
		(property "Value" ""
			(at 0 0 90)
			(layer "F.Fab")
			(effects
				(font
					(size 1.27 1.27)
				)
			)
		)
		(duplicate_pad_numbers_are_jumpers no)
		(fp_poly
			(pts
				(xy -0.2794 -0.1016) (xy 0.2794 -0.1016) (xy 0.2794 0.9906) (xy -0.2794 0.9906)
			)
			(stroke
				(width 0)
				(type default)
			)
			(fill no)
			(layer "F.CrtYd")
		)
		(fp_line
			(start 0.2794 -0.1016)
			(end -0.2794 -0.1016)
			(stroke
				(width 0.1)
				(type default)
			)
			(layer "F.Fab")
		)
		(fp_line
			(start -0.2794 -0.1016)
			(end -0.2794 0.9906)
			(stroke
				(width 0.1)
				(type default)
			)
			(layer "F.Fab")
		)
		(fp_line
			(start 0.2794 0.9906)
			(end 0.2794 -0.1016)
			(stroke
				(width 0.1)
				(type default)
			)
			(layer "F.Fab")
		)
		(fp_line
			(start -0.2794 0.9906)
			(end 0.2794 0.9906)
			(stroke
				(width 0.1)
				(type default)
			)
			(layer "F.Fab")
		)
		(pad "1" smd rect
			(at 0 0 90)
			(size 0.508 0.508)
			(layers "F.Cu" "F.Mask" "F.Paste")
			(net "VR_P5V_STBY_COMP")
		)
		(pad "2" smd rect
			(at 0 0.889 90)
			(size 0.508 0.508)
			(layers "F.Cu" "F.Mask" "F.Paste")
			(net "VR_P5V_STBY_RC_COMP")
		)
		(zone
			(layer "F.Cu")
			(hatch none 0.5)
			(connect_pads
				(clearance 0)
			)
			(min_thickness 0.25)
			(keepout
				(tracks allowed)
				(vias not_allowed)
				(pads allowed)
				(copperpour not_allowed)
				(footprints allowed)
			)
			(placement
				(enabled no)
				(sheetname "")
			)
			(fill
				(thermal_gap 0.5)
				(thermal_bridge_width 0.5)
				(island_removal_mode 0)
			)
			(polygon
				(pts
					(xy 393.039346 -64.705738) (xy 393.039346 -65.213738) (xy 393.420346 -65.213738) (xy 393.420346 -64.705738)
				)
			)
		)
		(zone
			(layer "F.Cu")
			(hatch none 0.5)
			(connect_pads
				(clearance 0)
			)
			(min_thickness 0.25)
			(keepout
				(tracks not_allowed)
				(vias allowed)
				(pads allowed)
				(copperpour not_allowed)
				(footprints allowed)
			)
			(placement
				(enabled no)
				(sheetname "")
			)
			(fill
				(thermal_gap 0.5)
				(thermal_bridge_width 0.5)
				(island_removal_mode 0)
			)
			(polygon
				(pts
					(xy 393.420346 -64.705738) (xy 393.420346 -65.213738) (xy 393.039346 -65.213738) (xy 393.039346 -64.705738)
				)
			)
		)
	)
	(footprint ""
		(layer "F.Cu")
		(at 214.503 -78.4098)
		(property "Reference" "C4D12"
			(at 0 0 0)
			(layer "F.SilkS")
			(hide yes)
			(effects
				(font
					(size 1.27 1.27)
				)
			)
		)
		(property "Value" ""
			(at 0 0 0)
			(layer "F.Fab")
			(effects
				(font
					(size 1.27 1.27)
				)
			)
		)
		(duplicate_pad_numbers_are_jumpers no)
		(fp_poly
			(pts
				(xy -0.4953 -0.2032) (xy 0.4953 -0.2032) (xy 0.4953 1.6002) (xy -0.4953 1.6002)
			)
			(stroke
				(width 0)
				(type default)
			)
			(fill no)
			(layer "F.CrtYd")
		)
		(fp_line
			(start -0.4953 -0.2032)
			(end 0.4953 -0.2032)
			(stroke
				(width 0.1)
				(type default)
			)
			(layer "F.Fab")
		)
		(fp_line
			(start -0.4953 1.6002)
			(end -0.4953 -0.2032)
			(stroke
				(width 0.1)
				(type default)
			)
			(layer "F.Fab")
		)
		(fp_line
			(start 0.4953 -0.2032)
			(end 0.4953 1.6002)
			(stroke
				(width 0.1)
				(type default)
			)
			(layer "F.Fab")
		)
		(fp_line
			(start 0.4953 1.6002)
			(end -0.4953 1.6002)
			(stroke
				(width 0.1)
				(type default)
			)
			(layer "F.Fab")
		)
		(pad "1" smd rect
			(at 0 0)
			(size 0.762 0.889)
			(layers "F.Cu" "F.Mask" "F.Paste")
			(net "PVCCIN_CPU0")
		)
		(pad "2" smd rect
			(at 0 1.397)
			(size 0.762 0.889)
			(layers "F.Cu" "F.Mask" "F.Paste")
			(net "GND")
		)
		(zone
			(layer "F.Cu")
			(hatch none 0.5)
			(connect_pads
				(clearance 0)
			)
			(min_thickness 0.25)
			(keepout
				(tracks not_allowed)
				(vias allowed)
				(pads allowed)
				(copperpour not_allowed)
				(footprints allowed)
			)
			(placement
				(enabled no)
				(sheetname "")
			)
			(fill
				(thermal_gap 0.5)
				(thermal_bridge_width 0.5)
				(island_removal_mode 0)
			)
			(polygon
				(pts
					(xy 214.122 -77.9653) (xy 214.884 -77.9653) (xy 214.884 -77.4573) (xy 214.122 -77.4573)
				)
			)
		)
	)
	(footprint ""
		(layer "F.Cu")
		(at 386.417566 -141.471396 -90)
		(property "Reference" "C7B18"
			(at 0 0 270)
			(layer "F.SilkS")
			(hide yes)
			(effects
				(font
					(size 1.27 1.27)
				)
			)
		)
		(property "Value" ""
			(at 0 0 270)
			(layer "F.Fab")
			(effects
				(font
					(size 1.27 1.27)
				)
			)
		)
		(duplicate_pad_numbers_are_jumpers no)
		(fp_rect
			(start -0.4953 1.6002)
			(end 0.4953 -0.2032)
			(stroke
				(width 0)
				(type default)
			)
			(fill no)
			(layer "F.CrtYd")
		)
		(fp_line
			(start -0.4953 1.6002)
			(end -0.4953 -0.2032)
			(stroke
				(width 0.1)
				(type default)
			)
			(layer "F.Fab")
		)
		(fp_line
			(start 0.4953 1.6002)
			(end -0.4953 1.6002)
			(stroke
				(width 0.1)
				(type default)
			)
			(layer "F.Fab")
		)
		(fp_line
			(start -0.4953 -0.2032)
			(end 0.4953 -0.2032)
			(stroke
				(width 0.1)
				(type default)
			)
			(layer "F.Fab")
		)
		(fp_line
			(start 0.4953 -0.2032)
			(end 0.4953 1.6002)
			(stroke
				(width 0.1)
				(type default)
			)
			(layer "F.Fab")
		)
		(pad "1" smd rect
			(at 0 0 270)
			(size 0.762 0.889)
			(layers "F.Cu" "F.Mask" "F.Paste")
			(net "P1V05_PCH_STBY")
		)
		(pad "2" smd rect
			(at 0 1.397 270)
			(size 0.762 0.889)
			(layers "F.Cu" "F.Mask" "F.Paste")
			(net "GND")
		)
		(zone
			(layer "F.Cu")
			(hatch none 0.5)
			(connect_pads
				(clearance 0)
			)
			(min_thickness 0.25)
			(keepout
				(tracks not_allowed)
				(vias allowed)
				(pads allowed)
				(copperpour not_allowed)
				(footprints allowed)
			)
			(placement
				(enabled no)
				(sheetname "")
			)
			(fill
				(thermal_gap 0.5)
				(thermal_bridge_width 0.5)
				(island_removal_mode 0)
			)
			(polygon
				(pts
					(xy 385.465066 -141.852396) (xy 385.465066 -141.090396) (xy 385.973066 -141.090396) (xy 385.973066 -141.852396)
				)
			)
		)
	)
)
